(kicad_pcb
	(version 20260206)
	(generator "pcbnew")
	(generator_version "10.0")
	(general
		(thickness 1.6)
		(legacy_teardrops no)
	)
	(paper "A4")
	(title_block
		(title "12092022_DA0F0TMDCD0_F0T_Management_Board_D_brd_V3_OCP.brd")
		(comment 1 "Grand Teton / footprints 1196-1201 of 1440")
	)
	(layers
		(0 "F.Cu" signal "TOP")
		(4 "In1.Cu" signal "GND")
		(6 "In2.Cu" signal "IN1")
		(8 "In3.Cu" signal "GND1")
		(10 "In4.Cu" signal "IN2")
		(12 "In5.Cu" signal "VCC")
		(14 "In6.Cu" signal "VCC1")
		(16 "In7.Cu" signal "IN3")
		(18 "In8.Cu" signal "GND2")
		(20 "In9.Cu" signal "IN4")
		(22 "In10.Cu" signal "GND3")
		(2 "B.Cu" signal "BOTTOM")
		(9 "F.Adhes" user "F.Adhesive")
		(11 "B.Adhes" user "B.Adhesive")
		(13 "F.Paste" user "Package Geometry/Pastemask Top")
		(15 "B.Paste" user "Package Geometry/Pastemask Bottom")
		(5 "F.SilkS" user "Ref Des/Silkscreen Top")
		(7 "B.SilkS" user "Ref Des/Silkscreen Bottom")
		(1 "F.Mask" user "Board Geometry/Soldermask Top")
		(3 "B.Mask" user "Board Geometry/Soldermask Bottom")
		(17 "Dwgs.User" user "User.Drawings")
		(19 "Cmts.User" user "User.Comments")
		(21 "Eco1.User" user "User.Eco1")
		(23 "Eco2.User" user "User.Eco2")
		(25 "Edge.Cuts" user "Board Geometry/Outline")
		(27 "Margin" user)
		(31 "F.CrtYd" user "Package Geometry/Place Bound Top")
		(29 "B.CrtYd" user "Package Geometry/Place Bound Bottom")
		(35 "F.Fab" user "Ref Des/Assembly Top")
		(33 "B.Fab" user "Ref Des/Assembly Bottom")
	)
	(footprint ""
		(layer "B.Cu")
		(at 56.134 -62.4332 180)
		(property "Reference" "R401"
			(at 0 0 0)
			(layer "B.SilkS")
			(hide yes)
			(effects
				(font
					(size 1.27 1.27)
				)
				(justify mirror)
			)
		)
		(property "Value" ""
			(at 0 0 0)
			(layer "B.Fab")
			(effects
				(font
					(size 1.27 1.27)
				)
				(justify mirror)
			)
		)
		(duplicate_pad_numbers_are_jumpers no)
		(fp_line
			(start 0.7874 0.4064)
			(end 0.7874 -0.4064)
			(stroke
				(width 0.1524)
				(type default)
			)
			(layer "B.SilkS")
		)
		(fp_line
			(start 0.7874 -0.4064)
			(end -0.7874 -0.4064)
			(stroke
				(width 0.1524)
				(type default)
			)
			(layer "B.SilkS")
		)
		(fp_line
			(start -0.7874 0.4064)
			(end 0.7874 0.4064)
			(stroke
				(width 0.1524)
				(type default)
			)
			(layer "B.SilkS")
		)
		(fp_line
			(start -0.7874 -0.4064)
			(end -0.7874 0.4064)
			(stroke
				(width 0.1524)
				(type default)
			)
			(layer "B.SilkS")
		)
		(fp_line
			(start 0.67945 0.3048)
			(end 0.67945 -0.305054)
			(stroke
				(width 0.1)
				(type default)
			)
			(layer "B.Fab")
		)
		(fp_line
			(start 0.67945 -0.305054)
			(end 0.12065 -0.305054)
			(stroke
				(width 0.1)
				(type default)
			)
			(layer "B.Fab")
		)
		(fp_line
			(start 0.12065 0.3048)
			(end 0.67945 0.3048)
			(stroke
				(width 0.1)
				(type default)
			)
			(layer "B.Fab")
		)
		(fp_line
			(start 0.12065 0.2794)
			(end 0.12065 0.3048)
			(stroke
				(width 0.1)
				(type default)
			)
			(layer "B.Fab")
		)
		(fp_line
			(start 0.12065 -0.2794)
			(end -0.12065 -0.2794)
			(stroke
				(width 0.1)
				(type default)
			)
			(layer "B.Fab")
		)
		(fp_line
			(start 0.12065 -0.305054)
			(end 0.12065 -0.2794)
			(stroke
				(width 0.1)
				(type default)
			)
			(layer "B.Fab")
		)
		(fp_line
			(start -0.120396 0.3048)
			(end -0.120396 0.2794)
			(stroke
				(width 0.1)
				(type default)
			)
			(layer "B.Fab")
		)
		(fp_line
			(start -0.120396 0.2794)
			(end 0.12065 0.2794)
			(stroke
				(width 0.1)
				(type default)
			)
			(layer "B.Fab")
		)
		(fp_line
			(start -0.12065 -0.2794)
			(end -0.12065 -0.3048)
			(stroke
				(width 0.1)
				(type default)
			)
			(layer "B.Fab")
		)
		(fp_line
			(start -0.12065 -0.3048)
			(end -0.67945 -0.3048)
			(stroke
				(width 0.1)
				(type default)
			)
			(layer "B.Fab")
		)
		(fp_line
			(start -0.67945 0.3048)
			(end -0.120396 0.3048)
			(stroke
				(width 0.1)
				(type default)
			)
			(layer "B.Fab")
		)
		(fp_line
			(start -0.67945 -0.3048)
			(end -0.67945 0.3048)
			(stroke
				(width 0.1)
				(type default)
			)
			(layer "B.Fab")
		)
		(pad "1" smd circle
			(at 0.40005 0)
			(size 0 0)
			(layers "B.Cu" "B.Mask" "B.Paste")
			(net "PU_BMC_FWSPIABR_N")
		)
		(pad "2" smd circle
			(at -0.40005 0)
			(size 0 0)
			(layers "B.Cu" "B.Mask" "B.Paste")
			(net "PU_BMC_FWSPIABR_N_R")
		)
	)
	(footprint ""
		(layer "B.Cu")
		(at 47.607474 -30.857698 -90)
		(property "Reference" "R248"
			(at 0 0 90)
			(layer "B.SilkS")
			(hide yes)
			(effects
				(font
					(size 1.27 1.27)
				)
				(justify mirror)
			)
		)
		(property "Value" ""
			(at 0 0 90)
			(layer "B.Fab")
			(effects
				(font
					(size 1.27 1.27)
				)
				(justify mirror)
			)
		)
		(duplicate_pad_numbers_are_jumpers no)
		(fp_line
			(start -0.7874 0.4064)
			(end 0.7874 0.4064)
			(stroke
				(width 0.1524)
				(type default)
			)
			(layer "B.SilkS")
		)
		(fp_line
			(start 0.7874 0.4064)
			(end 0.7874 -0.4064)
			(stroke
				(width 0.1524)
				(type default)
			)
			(layer "B.SilkS")
		)
		(fp_line
			(start -0.7874 -0.4064)
			(end -0.7874 0.4064)
			(stroke
				(width 0.1524)
				(type default)
			)
			(layer "B.SilkS")
		)
		(fp_line
			(start 0.7874 -0.4064)
			(end -0.7874 -0.4064)
			(stroke
				(width 0.1524)
				(type default)
			)
			(layer "B.SilkS")
		)
		(fp_line
			(start -0.67945 0.3048)
			(end -0.120396 0.3048)
			(stroke
				(width 0.1)
				(type default)
			)
			(layer "B.Fab")
		)
		(fp_line
			(start -0.120396 0.3048)
			(end -0.120396 0.2794)
			(stroke
				(width 0.1)
				(type default)
			)
			(layer "B.Fab")
		)
		(fp_line
			(start 0.12065 0.3048)
			(end 0.67945 0.3048)
			(stroke
				(width 0.1)
				(type default)
			)
			(layer "B.Fab")
		)
		(fp_line
			(start 0.67945 0.3048)
			(end 0.67945 -0.305054)
			(stroke
				(width 0.1)
				(type default)
			)
			(layer "B.Fab")
		)
		(fp_line
			(start -0.120396 0.2794)
			(end 0.12065 0.2794)
			(stroke
				(width 0.1)
				(type default)
			)
			(layer "B.Fab")
		)
		(fp_line
			(start 0.12065 0.2794)
			(end 0.12065 0.3048)
			(stroke
				(width 0.1)
				(type default)
			)
			(layer "B.Fab")
		)
		(fp_line
			(start -0.12065 -0.2794)
			(end -0.12065 -0.3048)
			(stroke
				(width 0.1)
				(type default)
			)
			(layer "B.Fab")
		)
		(fp_line
			(start 0.12065 -0.2794)
			(end -0.12065 -0.2794)
			(stroke
				(width 0.1)
				(type default)
			)
			(layer "B.Fab")
		)
		(fp_line
			(start -0.67945 -0.3048)
			(end -0.67945 0.3048)
			(stroke
				(width 0.1)
				(type default)
			)
			(layer "B.Fab")
		)
		(fp_line
			(start -0.12065 -0.3048)
			(end -0.67945 -0.3048)
			(stroke
				(width 0.1)
				(type default)
			)
			(layer "B.Fab")
		)
		(fp_line
			(start 0.12065 -0.305054)
			(end 0.12065 -0.2794)
			(stroke
				(width 0.1)
				(type default)
			)
			(layer "B.Fab")
		)
		(fp_line
			(start 0.67945 -0.305054)
			(end 0.12065 -0.305054)
			(stroke
				(width 0.1)
				(type default)
			)
			(layer "B.Fab")
		)
		(pad "1" smd circle
			(at 0.40005 0 90)
			(size 0 0)
			(layers "B.Cu" "B.Mask" "B.Paste")
			(net "P3V3_AUX")
		)
		(pad "2" smd circle
			(at -0.40005 0 90)
			(size 0 0)
			(layers "B.Cu" "B.Mask" "B.Paste")
			(net "SMB_BMC_MM3_SCL")
		)
	)
	(footprint ""
		(layer "B.Cu")
		(at 56.695848 -49.246028)
		(property "Reference" "C109"
			(at 0 0 0)
			(layer "B.SilkS")
			(hide yes)
			(effects
				(font
					(size 1.27 1.27)
				)
				(justify mirror)
			)
		)
		(property "Value" ""
			(at 0 0 0)
			(layer "B.Fab")
			(effects
				(font
					(size 1.27 1.27)
				)
				(justify mirror)
			)
		)
		(duplicate_pad_numbers_are_jumpers no)
		(fp_line
			(start -0.7874 -0.4064)
			(end -0.7874 0.4064)
			(stroke
				(width 0.1524)
				(type default)
			)
			(layer "B.SilkS")
		)
		(fp_line
			(start -0.7874 0.4064)
			(end 0.7874 0.4064)
			(stroke
				(width 0.1524)
				(type default)
			)
			(layer "B.SilkS")
		)
		(fp_line
			(start 0.7874 -0.4064)
			(end -0.7874 -0.4064)
			(stroke
				(width 0.1524)
				(type default)
			)
			(layer "B.SilkS")
		)
		(fp_line
			(start 0.7874 0.4064)
			(end 0.7874 -0.4064)
			(stroke
				(width 0.1524)
				(type default)
			)
			(layer "B.SilkS")
		)
		(fp_line
			(start -0.67945 -0.3048)
			(end -0.67945 0.3048)
			(stroke
				(width 0.1)
				(type default)
			)
			(layer "B.Fab")
		)
		(fp_line
			(start -0.67945 0.3048)
			(end -0.120396 0.3048)
			(stroke
				(width 0.1)
				(type default)
			)
			(layer "B.Fab")
		)
		(fp_line
			(start -0.12065 -0.3048)
			(end -0.67945 -0.3048)
			(stroke
				(width 0.1)
				(type default)
			)
			(layer "B.Fab")
		)
		(fp_line
			(start -0.12065 -0.2794)
			(end -0.12065 -0.3048)
			(stroke
				(width 0.1)
				(type default)
			)
			(layer "B.Fab")
		)
		(fp_line
			(start -0.120396 0.2794)
			(end 0.12065 0.2794)
			(stroke
				(width 0.1)
				(type default)
			)
			(layer "B.Fab")
		)
		(fp_line
			(start -0.120396 0.3048)
			(end -0.120396 0.2794)
			(stroke
				(width 0.1)
				(type default)
			)
			(layer "B.Fab")
		)
		(fp_line
			(start 0.12065 -0.305054)
			(end 0.12065 -0.2794)
			(stroke
				(width 0.1)
				(type default)
			)
			(layer "B.Fab")
		)
		(fp_line
			(start 0.12065 -0.2794)
			(end -0.12065 -0.2794)
			(stroke
				(width 0.1)
				(type default)
			)
			(layer "B.Fab")
		)
		(fp_line
			(start 0.12065 0.2794)
			(end 0.12065 0.3048)
			(stroke
				(width 0.1)
				(type default)
			)
			(layer "B.Fab")
		)
		(fp_line
			(start 0.12065 0.3048)
			(end 0.67945 0.3048)
			(stroke
				(width 0.1)
				(type default)
			)
			(layer "B.Fab")
		)
		(fp_line
			(start 0.67945 -0.305054)
			(end 0.12065 -0.305054)
			(stroke
				(width 0.1)
				(type default)
			)
			(layer "B.Fab")
		)
		(fp_line
			(start 0.67945 0.3048)
			(end 0.67945 -0.305054)
			(stroke
				(width 0.1)
				(type default)
			)
			(layer "B.Fab")
		)
		(pad "1" smd circle
			(at 0.40005 0 180)
			(size 0 0)
			(layers "B.Cu" "B.Mask" "B.Paste")
			(net "P1V8_AUX")
		)
		(pad "2" smd circle
			(at -0.40005 0 180)
			(size 0 0)
			(layers "B.Cu" "B.Mask" "B.Paste")
			(net "GND")
		)
	)
	(footprint ""
		(layer "B.Cu")
		(at 50.23866 -69.397372 90)
		(property "Reference" "R789"
			(at 0 0 90)
			(layer "B.SilkS")
			(hide yes)
			(effects
				(font
					(size 1.27 1.27)
				)
				(justify mirror)
			)
		)
		(property "Value" ""
			(at 0 0 90)
			(layer "B.Fab")
			(effects
				(font
					(size 1.27 1.27)
				)
				(justify mirror)
			)
		)
		(duplicate_pad_numbers_are_jumpers no)
		(fp_line
			(start 0.7874 -0.4064)
			(end -0.7874 -0.4064)
			(stroke
				(width 0.1524)
				(type default)
			)
			(layer "B.SilkS")
		)
		(fp_line
			(start -0.7874 -0.4064)
			(end -0.7874 0.4064)
			(stroke
				(width 0.1524)
				(type default)
			)
			(layer "B.SilkS")
		)
		(fp_line
			(start 0.7874 0.4064)
			(end 0.7874 -0.4064)
			(stroke
				(width 0.1524)
				(type default)
			)
			(layer "B.SilkS")
		)
		(fp_line
			(start -0.7874 0.4064)
			(end 0.7874 0.4064)
			(stroke
				(width 0.1524)
				(type default)
			)
			(layer "B.SilkS")
		)
		(fp_line
			(start 0.67945 -0.305054)
			(end 0.12065 -0.305054)
			(stroke
				(width 0.1)
				(type default)
			)
			(layer "B.Fab")
		)
		(fp_line
			(start 0.12065 -0.305054)
			(end 0.12065 -0.2794)
			(stroke
				(width 0.1)
				(type default)
			)
			(layer "B.Fab")
		)
		(fp_line
			(start -0.12065 -0.3048)
			(end -0.67945 -0.3048)
			(stroke
				(width 0.1)
				(type default)
			)
			(layer "B.Fab")
		)
		(fp_line
			(start -0.67945 -0.3048)
			(end -0.67945 0.3048)
			(stroke
				(width 0.1)
				(type default)
			)
			(layer "B.Fab")
		)
		(fp_line
			(start 0.12065 -0.2794)
			(end -0.12065 -0.2794)
			(stroke
				(width 0.1)
				(type default)
			)
			(layer "B.Fab")
		)
		(fp_line
			(start -0.12065 -0.2794)
			(end -0.12065 -0.3048)
			(stroke
				(width 0.1)
				(type default)
			)
			(layer "B.Fab")
		)
		(fp_line
			(start 0.12065 0.2794)
			(end 0.12065 0.3048)
			(stroke
				(width 0.1)
				(type default)
			)
			(layer "B.Fab")
		)
		(fp_line
			(start -0.120396 0.2794)
			(end 0.12065 0.2794)
			(stroke
				(width 0.1)
				(type default)
			)
			(layer "B.Fab")
		)
		(fp_line
			(start 0.67945 0.3048)
			(end 0.67945 -0.305054)
			(stroke
				(width 0.1)
				(type default)
			)
			(layer "B.Fab")
		)
		(fp_line
			(start 0.12065 0.3048)
			(end 0.67945 0.3048)
			(stroke
				(width 0.1)
				(type default)
			)
			(layer "B.Fab")
		)
		(fp_line
			(start -0.120396 0.3048)
			(end -0.120396 0.2794)
			(stroke
				(width 0.1)
				(type default)
			)
			(layer "B.Fab")
		)
		(fp_line
			(start -0.67945 0.3048)
			(end -0.120396 0.3048)
			(stroke
				(width 0.1)
				(type default)
			)
			(layer "B.Fab")
		)
		(pad "1" smd circle
			(at 0.40005 0 270)
			(size 0 0)
			(layers "B.Cu" "B.Mask" "B.Paste")
			(net "P3V3_AUX")
		)
		(pad "2" smd circle
			(at -0.40005 0 270)
			(size 0 0)
			(layers "B.Cu" "B.Mask" "B.Paste")
			(net "P3V3_SENSOR")
		)
	)
	(footprint ""
		(layer "B.Cu")
		(at 14.097 -20.447 -90)
		(property "Reference" "R814"
			(at 0 0 90)
			(layer "B.SilkS")
			(hide yes)
			(effects
				(font
					(size 1.27 1.27)
				)
				(justify mirror)
			)
		)
		(property "Value" ""
			(at 0 0 90)
			(layer "B.Fab")
			(effects
				(font
					(size 1.27 1.27)
				)
				(justify mirror)
			)
		)
		(duplicate_pad_numbers_are_jumpers no)
		(fp_line
			(start -0.7874 0.4064)
			(end 0.7874 0.4064)
			(stroke
				(width 0.1524)
				(type default)
			)
			(layer "B.SilkS")
		)
		(fp_line
			(start 0.7874 0.4064)
			(end 0.7874 -0.4064)
			(stroke
				(width 0.1524)
				(type default)
			)
			(layer "B.SilkS")
		)
		(fp_line
			(start -0.7874 -0.4064)
			(end -0.7874 0.4064)
			(stroke
				(width 0.1524)
				(type default)
			)
			(layer "B.SilkS")
		)
		(fp_line
			(start 0.7874 -0.4064)
			(end -0.7874 -0.4064)
			(stroke
				(width 0.1524)
				(type default)
			)
			(layer "B.SilkS")
		)
		(fp_line
			(start -0.67945 0.3048)
			(end -0.120396 0.3048)
			(stroke
				(width 0.1)
				(type default)
			)
			(layer "B.Fab")
		)
		(fp_line
			(start -0.120396 0.3048)
			(end -0.120396 0.2794)
			(stroke
				(width 0.1)
				(type default)
			)
			(layer "B.Fab")
		)
		(fp_line
			(start 0.12065 0.3048)
			(end 0.67945 0.3048)
			(stroke
				(width 0.1)
				(type default)
			)
			(layer "B.Fab")
		)
		(fp_line
			(start 0.67945 0.3048)
			(end 0.67945 -0.305054)
			(stroke
				(width 0.1)
				(type default)
			)
			(layer "B.Fab")
		)
		(fp_line
			(start -0.120396 0.2794)
			(end 0.12065 0.2794)
			(stroke
				(width 0.1)
				(type default)
			)
			(layer "B.Fab")
		)
		(fp_line
			(start 0.12065 0.2794)
			(end 0.12065 0.3048)
			(stroke
				(width 0.1)
				(type default)
			)
			(layer "B.Fab")
		)
		(fp_line
			(start -0.12065 -0.2794)
			(end -0.12065 -0.3048)
			(stroke
				(width 0.1)
				(type default)
			)
			(layer "B.Fab")
		)
		(fp_line
			(start 0.12065 -0.2794)
			(end -0.12065 -0.2794)
			(stroke
				(width 0.1)
				(type default)
			)
			(layer "B.Fab")
		)
		(fp_line
			(start -0.67945 -0.3048)
			(end -0.67945 0.3048)
			(stroke
				(width 0.1)
				(type default)
			)
			(layer "B.Fab")
		)
		(fp_line
			(start -0.12065 -0.3048)
			(end -0.67945 -0.3048)
			(stroke
				(width 0.1)
				(type default)
			)
			(layer "B.Fab")
		)
		(fp_line
			(start 0.12065 -0.305054)
			(end 0.12065 -0.2794)
			(stroke
				(width 0.1)
				(type default)
			)
			(layer "B.Fab")
		)
		(fp_line
			(start 0.67945 -0.305054)
			(end 0.12065 -0.305054)
			(stroke
				(width 0.1)
				(type default)
			)
			(layer "B.Fab")
		)
		(pad "1" smd circle
			(at 0.40005 0 90)
			(size 0 0)
			(layers "B.Cu" "B.Mask" "B.Paste")
			(net "P5V_AUX")
		)
		(pad "2" smd circle
			(at -0.40005 0 90)
			(size 0 0)
			(layers "B.Cu" "B.Mask" "B.Paste")
			(net "PWR_LED_BUF_N_R")
		)
	)
	(footprint ""
		(layer "B.Cu")
		(at 69.102478 -65.406016 90)
		(property "Reference" "L14"
			(at 0 0 90)
			(layer "B.SilkS")
			(hide yes)
			(effects
				(font
					(size 1.27 1.27)
				)
				(justify mirror)
			)
		)
		(property "Value" ""
			(at 0 0 90)
			(layer "B.Fab")
			(effects
				(font
					(size 1.27 1.27)
				)
				(justify mirror)
			)
		)
		(duplicate_pad_numbers_are_jumpers no)
		(fp_line
			(start 1.27 -0.5842)
			(end -1.27 -0.5842)
			(stroke
				(width 0.1524)
				(type default)
			)
			(layer "B.SilkS")
		)
		(fp_line
			(start 1.27 -0.5588)
			(end 1.27 -0.5842)
			(stroke
				(width 0.1524)
				(type default)
			)
			(layer "B.SilkS")
		)
		(fp_line
			(start 1.27 0.5842)
			(end 1.27 -0.5842)
			(stroke
				(width 0.1524)
				(type default)
			)
			(layer "B.SilkS")
		)
		(fp_line
			(start 0.127 0.5842)
			(end 0.127 -0.5842)
			(stroke
				(width 0.1524)
				(type default)
			)
			(layer "B.SilkS")
		)
		(fp_line
			(start -0.127 0.5842)
			(end -0.127 -0.5842)
			(stroke
				(width 0.1524)
				(type default)
			)
			(layer "B.SilkS")
		)
		(fp_line
			(start -1.27 0.5842)
			(end -1.27 -0.5842)
			(stroke
				(width 0.1524)
				(type default)
			)
			(layer "B.SilkS")
		)
		(fp_line
			(start -1.27 0.5842)
			(end 1.27 0.5842)
			(stroke
				(width 0.1524)
				(type default)
			)
			(layer "B.SilkS")
		)
		(fp_line
			(start 0.9144 -0.508)
			(end -0.9144 -0.508)
			(stroke
				(width 0.1)
				(type default)
			)
			(layer "B.Fab")
		)
		(fp_line
			(start -0.9144 -0.508)
			(end -0.9144 -0.406654)
			(stroke
				(width 0.1)
				(type default)
			)
			(layer "B.Fab")
		)
		(fp_line
			(start 1.194308 -0.406654)
			(end 0.9144 -0.406654)
			(stroke
				(width 0.1)
				(type default)
			)
			(layer "B.Fab")
		)
		(fp_line
			(start 0.9144 -0.406654)
			(end 0.9144 -0.508)
			(stroke
				(width 0.1)
				(type default)
			)
			(layer "B.Fab")
		)
		(fp_line
			(start -0.9144 -0.406654)
			(end -1.1938 -0.406654)
			(stroke
				(width 0.1)
				(type default)
			)
			(layer "B.Fab")
		)
		(fp_line
			(start -1.1938 -0.406654)
			(end -1.1938 0.4064)
			(stroke
				(width 0.1)
				(type default)
			)
			(layer "B.Fab")
		)
		(fp_line
			(start -0.9144 0.4064)
			(end -0.9144 0.508)
			(stroke
				(width 0.1)
				(type default)
			)
			(layer "B.Fab")
		)
		(fp_line
			(start -1.1938 0.4064)
			(end -0.9144 0.4064)
			(stroke
				(width 0.1)
				(type default)
			)
			(layer "B.Fab")
		)
		(fp_line
			(start 1.194308 0.406654)
			(end 1.194308 -0.406654)
			(stroke
				(width 0.1)
				(type default)
			)
			(layer "B.Fab")
		)
		(fp_line
			(start 0.9144 0.406654)
			(end 1.194308 0.406654)
			(stroke
				(width 0.1)
				(type default)
			)
			(layer "B.Fab")
		)
		(fp_line
			(start 0.9144 0.508)
			(end 0.9144 0.406654)
			(stroke
				(width 0.1)
				(type default)
			)
			(layer "B.Fab")
		)
		(fp_line
			(start -0.9144 0.508)
			(end 0.9144 0.508)
			(stroke
				(width 0.1)
				(type default)
			)
			(layer "B.Fab")
		)
		(pad "1" smd rect
			(at 0.7366 0)
			(size 0.7112 0.8128)
			(layers "B.Cu" "B.Mask" "B.Paste")
			(net "P1V8_AUX")
		)
		(pad "2" smd rect
			(at -0.7366 0)
			(size 0.7112 0.8128)
			(layers "B.Cu" "B.Mask" "B.Paste")
			(net "P1V8_STBY_RC_VCC18A")
		)
	)
)
